# T6G (Grand Teton) — schematic netlist excerpt (pin names and nets, part order shuffled) for the footprints in the layout excerpt that follows; sources: Cadence DE-HDL packaged netlist, KiCad conversion of 04192023_DAF0TMB3IC0_F0TG_MB_C_brd_V02_OCP.brd

PC421  Q_CAP  2.2UF 10V 10% X6S  pkg C0402  page 220 : A = PVDDCR_CPU1_P1_VCC5 ; B = GND
R6712  Q_RES  1K 1% CHIP  pkg 0201LF  page 320 : A = P1V8_CPU1_RT_1D ; B = RT_CPU1_P0_ADDR3
PC75  Q_CAP  1UF 16V 10% X6S  pkg C0402  page 200 : A = PVDDCR_CPU1_P0_VCC ; B = GND

(kicad_pcb
	(version 20260206)
	(generator "pcbnew")
	(generator_version "10.0")
	(general
		(thickness 1.6)
		(legacy_teardrops no)
	)
	(paper "A4")
	(title_block
		(title "04192023_DAF0TMB3IC0_F0TG_MB_C_brd_V02_OCP.brd")
		(comment 1 "Grand Teton / footprints 2789-2791 of 8354")
	)
	(layers
		(0 "F.Cu" signal "TOP")
		(4 "In1.Cu" signal "GND")
		(6 "In2.Cu" signal "IN1")
		(8 "In3.Cu" signal "GND1")
		(10 "In4.Cu" signal "IN2")
		(12 "In5.Cu" signal "GND2")
		(14 "In6.Cu" signal "IN3")
		(16 "In7.Cu" signal "GND3")
		(18 "In8.Cu" signal "VCC")
		(20 "In9.Cu" signal "VCC1")
		(22 "In10.Cu" signal "GND4")
		(24 "In11.Cu" signal "IN4")
		(26 "In12.Cu" signal "GND5")
		(28 "In13.Cu" signal "IN5")
		(30 "In14.Cu" signal "GND6")
		(32 "In15.Cu" signal "IN6")
		(34 "In16.Cu" signal "GND7")
		(2 "B.Cu" signal "BOTTOM")
		(9 "F.Adhes" user "F.Adhesive")
		(11 "B.Adhes" user "B.Adhesive")
		(13 "F.Paste" user "Package Geometry/Pastemask Top")
		(15 "B.Paste" user "Package Geometry/Pastemask Bottom")
		(5 "F.SilkS" user "Ref Des/Silkscreen Top")
		(7 "B.SilkS" user "Ref Des/Silkscreen Bottom")
		(1 "F.Mask" user "Board Geometry/Soldermask Top")
		(3 "B.Mask" user "Board Geometry/Soldermask Bottom")
		(17 "Dwgs.User" user "User.Drawings")
		(19 "Cmts.User" user "User.Comments")
		(21 "Eco1.User" user "User.Eco1")
		(23 "Eco2.User" user "User.Eco2")
		(25 "Edge.Cuts" user "Board Geometry/Outline")
		(27 "Margin" user)
		(31 "F.CrtYd" user "Package Geometry/Place Bound Top")
		(29 "B.CrtYd" user "Package Geometry/Place Bound Bottom")
		(35 "F.Fab" user "Ref Des/Assembly Top")
		(33 "B.Fab" user "Ref Des/Assembly Bottom")
	)
	(footprint ""
		(layer "F.Cu")
		(at 91.770454 -337.694524 90)
		(property "Reference" "PC421"
			(at 0 0 90)
			(layer "F.SilkS")
			(hide yes)
			(effects
				(font
					(size 1.27 1.27)
				)
			)
		)
		(property "Value" ""
			(at 0 0 90)
			(layer "F.Fab")
			(effects
				(font
					(size 1.27 1.27)
				)
			)
		)
		(duplicate_pad_numbers_are_jumpers no)
		(fp_line
			(start 0.7874 -0.4064)
			(end 0.7874 0.4064)
			(stroke
				(width 0.1524)
				(type default)
			)
			(layer "F.SilkS")
		)
		(fp_line
			(start -0.7874 -0.4064)
			(end 0.7874 -0.4064)
			(stroke
				(width 0.1524)
				(type default)
			)
			(layer "F.SilkS")
		)
		(fp_line
			(start 0.7874 0.4064)
			(end 0.379476 0.4064)
			(stroke
				(width 0.1524)
				(type default)
			)
			(layer "F.SilkS")
		)
		(fp_line
			(start -0.230124 0.4064)
			(end -0.7874 0.4064)
			(stroke
				(width 0.1524)
				(type default)
			)
			(layer "F.SilkS")
		)
		(fp_line
			(start -0.7874 0.4064)
			(end -0.7874 -0.4064)
			(stroke
				(width 0.1524)
				(type default)
			)
			(layer "F.SilkS")
		)
		(fp_line
			(start -0.12065 -0.305054)
			(end -0.12065 -0.2794)
			(stroke
				(width 0.1)
				(type default)
			)
			(layer "F.Fab")
		)
		(fp_line
			(start -0.67945 -0.305054)
			(end -0.12065 -0.305054)
			(stroke
				(width 0.1)
				(type default)
			)
			(layer "F.Fab")
		)
		(fp_line
			(start 0.67945 -0.3048)
			(end 0.67945 0.3048)
			(stroke
				(width 0.1)
				(type default)
			)
			(layer "F.Fab")
		)
		(fp_line
			(start 0.12065 -0.3048)
			(end 0.67945 -0.3048)
			(stroke
				(width 0.1)
				(type default)
			)
			(layer "F.Fab")
		)
		(fp_line
			(start 0.12065 -0.2794)
			(end 0.12065 -0.3048)
			(stroke
				(width 0.1)
				(type default)
			)
			(layer "F.Fab")
		)
		(fp_line
			(start -0.12065 -0.2794)
			(end 0.12065 -0.2794)
			(stroke
				(width 0.1)
				(type default)
			)
			(layer "F.Fab")
		)
		(fp_line
			(start 0.120396 0.2794)
			(end -0.12065 0.2794)
			(stroke
				(width 0.1)
				(type default)
			)
			(layer "F.Fab")
		)
		(fp_line
			(start -0.12065 0.2794)
			(end -0.12065 0.3048)
			(stroke
				(width 0.1)
				(type default)
			)
			(layer "F.Fab")
		)
		(fp_line
			(start 0.67945 0.3048)
			(end 0.120396 0.3048)
			(stroke
				(width 0.1)
				(type default)
			)
			(layer "F.Fab")
		)
		(fp_line
			(start 0.120396 0.3048)
			(end 0.120396 0.2794)
			(stroke
				(width 0.1)
				(type default)
			)
			(layer "F.Fab")
		)
		(fp_line
			(start -0.12065 0.3048)
			(end -0.67945 0.3048)
			(stroke
				(width 0.1)
				(type default)
			)
			(layer "F.Fab")
		)
		(fp_line
			(start -0.67945 0.3048)
			(end -0.67945 -0.305054)
			(stroke
				(width 0.1)
				(type default)
			)
			(layer "F.Fab")
		)
		(pad "1" smd circle
			(at -0.40005 0 90)
			(size 0 0)
			(layers "F.Cu" "F.Mask" "F.Paste")
			(net "PVDDCR_CPU1_P1_VCC5")
		)
		(pad "2" smd circle
			(at 0.40005 0 90)
			(size 0 0)
			(layers "F.Cu" "F.Mask" "F.Paste")
			(net "GND")
		)
	)
	(footprint ""
		(layer "F.Cu")
		(at 71.882 -385.5212 90)
		(property "Reference" "R6712"
			(at 0 0 90)
			(layer "F.SilkS")
			(hide yes)
			(effects
				(font
					(size 1.27 1.27)
				)
			)
		)
		(property "Value" ""
			(at 0 0 90)
			(layer "F.Fab")
			(effects
				(font
					(size 1.27 1.27)
				)
			)
		)
		(duplicate_pad_numbers_are_jumpers no)
		(fp_line
			(start 0.32512 -0.175006)
			(end 0.32512 0.175006)
			(stroke
				(width 0.1)
				(type default)
			)
			(layer "F.Fab")
		)
		(fp_line
			(start -0.32512 -0.175006)
			(end 0.32512 -0.175006)
			(stroke
				(width 0.1)
				(type default)
			)
			(layer "F.Fab")
		)
		(fp_line
			(start 0.32512 0.175006)
			(end -0.32512 0.175006)
			(stroke
				(width 0.1)
				(type default)
			)
			(layer "F.Fab")
		)
		(fp_line
			(start -0.32512 0.175006)
			(end -0.32512 -0.175006)
			(stroke
				(width 0.1)
				(type default)
			)
			(layer "F.Fab")
		)
		(pad "1" smd rect
			(at -0.2667 0 90)
			(size 0.3048 0.381)
			(layers "F.Cu" "F.Mask" "F.Paste")
			(net "P1V8_CPU1_RT_1D")
		)
		(pad "2" smd rect
			(at 0.2667 0 270)
			(size 0.3048 0.381)
			(layers "F.Cu" "F.Mask" "F.Paste")
			(net "RT_CPU1_P0_ADDR3")
		)
	)
	(footprint ""
		(layer "F.Cu")
		(at 317.246 -364.617 90)
		(property "Reference" "PC75"
			(at 0 0 90)
			(layer "F.SilkS")
			(hide yes)
			(effects
				(font
					(size 1.27 1.27)
				)
			)
		)
		(property "Value" ""
			(at 0 0 90)
			(layer "F.Fab")
			(effects
				(font
					(size 1.27 1.27)
				)
			)
		)
		(duplicate_pad_numbers_are_jumpers no)
		(fp_line
			(start 0.7874 -0.4064)
			(end 0.7874 0.4064)
			(stroke
				(width 0.1524)
				(type default)
			)
			(layer "F.SilkS")
		)
		(fp_line
			(start -0.7874 -0.4064)
			(end 0.7874 -0.4064)
			(stroke
				(width 0.1524)
				(type default)
			)
			(layer "F.SilkS")
		)
		(fp_line
			(start 0.7874 0.4064)
			(end -0.7874 0.4064)
			(stroke
				(width 0.1524)
				(type default)
			)
			(layer "F.SilkS")
		)
		(fp_line
			(start -0.7874 0.4064)
			(end -0.7874 -0.4064)
			(stroke
				(width 0.1524)
				(type default)
			)
			(layer "F.SilkS")
		)
		(fp_line
			(start -0.12065 -0.305054)
			(end -0.12065 -0.2794)
			(stroke
				(width 0.1)
				(type default)
			)
			(layer "F.Fab")
		)
		(fp_line
			(start -0.67945 -0.305054)
			(end -0.12065 -0.305054)
			(stroke
				(width 0.1)
				(type default)
			)
			(layer "F.Fab")
		)
		(fp_line
			(start 0.67945 -0.3048)
			(end 0.67945 0.3048)
			(stroke
				(width 0.1)
				(type default)
			)
			(layer "F.Fab")
		)
		(fp_line
			(start 0.12065 -0.3048)
			(end 0.67945 -0.3048)
			(stroke
				(width 0.1)
				(type default)
			)
			(layer "F.Fab")
		)
		(fp_line
			(start 0.12065 -0.2794)
			(end 0.12065 -0.3048)
			(stroke
				(width 0.1)
				(type default)
			)
			(layer "F.Fab")
		)
		(fp_line
			(start -0.12065 -0.2794)
			(end 0.12065 -0.2794)
			(stroke
				(width 0.1)
				(type default)
			)
			(layer "F.Fab")
		)
		(fp_line
			(start 0.120396 0.2794)
			(end -0.12065 0.2794)
			(stroke
				(width 0.1)
				(type default)
			)
			(layer "F.Fab")
		)
		(fp_line
			(start -0.12065 0.2794)
			(end -0.12065 0.3048)
			(stroke
				(width 0.1)
				(type default)
			)
			(layer "F.Fab")
		)
		(fp_line
			(start 0.67945 0.3048)
			(end 0.120396 0.3048)
			(stroke
				(width 0.1)
				(type default)
			)
			(layer "F.Fab")
		)
		(fp_line
			(start 0.120396 0.3048)
			(end 0.120396 0.2794)
			(stroke
				(width 0.1)
				(type default)
			)
			(layer "F.Fab")
		)
		(fp_line
			(start -0.12065 0.3048)
			(end -0.67945 0.3048)
			(stroke
				(width 0.1)
				(type default)
			)
			(layer "F.Fab")
		)
		(fp_line
			(start -0.67945 0.3048)
			(end -0.67945 -0.305054)
			(stroke
				(width 0.1)
				(type default)
			)
			(layer "F.Fab")
		)
		(pad "1" smd circle
			(at -0.40005 0 90)
			(size 0 0)
			(layers "F.Cu" "F.Mask" "F.Paste")
			(net "PVDDCR_CPU1_P0_VCC")
		)
		(pad "2" smd circle
			(at 0.40005 0 90)
			(size 0 0)
			(layers "F.Cu" "F.Mask" "F.Paste")
			(net "GND")
		)
	)
)
